(kicad_pcb
	(version 20260206)
	(generator "pcbnew")
	(generator_version "10.0")
	(general
		(thickness 1.6)
		(legacy_teardrops no)
	)
	(paper "A4")
	(title_block
		(title "04192023_DAF0TMB3IC0_F0TG_MB_C_brd_V02_OCP.brd")
		(comment 1 "Grand Teton / footprints 6623-6629 of 8354")
	)
	(layers
		(0 "F.Cu" signal "TOP")
		(4 "In1.Cu" signal "GND")
		(6 "In2.Cu" signal "IN1")
		(8 "In3.Cu" signal "GND1")
		(10 "In4.Cu" signal "IN2")
		(12 "In5.Cu" signal "GND2")
		(14 "In6.Cu" signal "IN3")
		(16 "In7.Cu" signal "GND3")
		(18 "In8.Cu" signal "VCC")
		(20 "In9.Cu" signal "VCC1")
		(22 "In10.Cu" signal "GND4")
		(24 "In11.Cu" signal "IN4")
		(26 "In12.Cu" signal "GND5")
		(28 "In13.Cu" signal "IN5")
		(30 "In14.Cu" signal "GND6")
		(32 "In15.Cu" signal "IN6")
		(34 "In16.Cu" signal "GND7")
		(2 "B.Cu" signal "BOTTOM")
		(9 "F.Adhes" user "F.Adhesive")
		(11 "B.Adhes" user "B.Adhesive")
		(13 "F.Paste" user "Package Geometry/Pastemask Top")
		(15 "B.Paste" user "Package Geometry/Pastemask Bottom")
		(5 "F.SilkS" user "Ref Des/Silkscreen Top")
		(7 "B.SilkS" user "Ref Des/Silkscreen Bottom")
		(1 "F.Mask" user "Board Geometry/Soldermask Top")
		(3 "B.Mask" user "Board Geometry/Soldermask Bottom")
		(17 "Dwgs.User" user "User.Drawings")
		(19 "Cmts.User" user "User.Comments")
		(21 "Eco1.User" user "User.Eco1")
		(23 "Eco2.User" user "User.Eco2")
		(25 "Edge.Cuts" user "Board Geometry/Outline")
		(27 "Margin" user)
		(31 "F.CrtYd" user "Package Geometry/Place Bound Top")
		(29 "B.CrtYd" user "Package Geometry/Place Bound Bottom")
		(35 "F.Fab" user "Ref Des/Assembly Top")
		(33 "B.Fab" user "Ref Des/Assembly Bottom")
	)
	(footprint ""
		(layer "B.Cu")
		(at 163.387532 -430.59858 90)
		(property "Reference" "R4124"
			(at 0 0 90)
			(layer "B.SilkS")
			(hide yes)
			(effects
				(font
					(size 1.27 1.27)
				)
				(justify mirror)
			)
		)
		(property "Value" ""
			(at 0 0 90)
			(layer "B.Fab")
			(effects
				(font
					(size 1.27 1.27)
				)
				(justify mirror)
			)
		)
		(duplicate_pad_numbers_are_jumpers no)
		(fp_line
			(start 0.7874 -0.4064)
			(end -0.7874 -0.4064)
			(stroke
				(width 0.1524)
				(type default)
			)
			(layer "B.SilkS")
		)
		(fp_line
			(start -0.7874 -0.4064)
			(end -0.7874 0.4064)
			(stroke
				(width 0.1524)
				(type default)
			)
			(layer "B.SilkS")
		)
		(fp_line
			(start 0.7874 0.4064)
			(end 0.7874 -0.4064)
			(stroke
				(width 0.1524)
				(type default)
			)
			(layer "B.SilkS")
		)
		(fp_line
			(start -0.7874 0.4064)
			(end 0.7874 0.4064)
			(stroke
				(width 0.1524)
				(type default)
			)
			(layer "B.SilkS")
		)
		(fp_line
			(start 0.67945 -0.305054)
			(end 0.12065 -0.305054)
			(stroke
				(width 0.1)
				(type default)
			)
			(layer "B.Fab")
		)
		(fp_line
			(start 0.12065 -0.305054)
			(end 0.12065 -0.2794)
			(stroke
				(width 0.1)
				(type default)
			)
			(layer "B.Fab")
		)
		(fp_line
			(start -0.12065 -0.3048)
			(end -0.67945 -0.3048)
			(stroke
				(width 0.1)
				(type default)
			)
			(layer "B.Fab")
		)
		(fp_line
			(start -0.67945 -0.3048)
			(end -0.67945 0.3048)
			(stroke
				(width 0.1)
				(type default)
			)
			(layer "B.Fab")
		)
		(fp_line
			(start 0.12065 -0.2794)
			(end -0.12065 -0.2794)
			(stroke
				(width 0.1)
				(type default)
			)
			(layer "B.Fab")
		)
		(fp_line
			(start -0.12065 -0.2794)
			(end -0.12065 -0.3048)
			(stroke
				(width 0.1)
				(type default)
			)
			(layer "B.Fab")
		)
		(fp_line
			(start 0.12065 0.2794)
			(end 0.12065 0.3048)
			(stroke
				(width 0.1)
				(type default)
			)
			(layer "B.Fab")
		)
		(fp_line
			(start -0.120396 0.2794)
			(end 0.12065 0.2794)
			(stroke
				(width 0.1)
				(type default)
			)
			(layer "B.Fab")
		)
		(fp_line
			(start 0.67945 0.3048)
			(end 0.67945 -0.305054)
			(stroke
				(width 0.1)
				(type default)
			)
			(layer "B.Fab")
		)
		(fp_line
			(start 0.12065 0.3048)
			(end 0.67945 0.3048)
			(stroke
				(width 0.1)
				(type default)
			)
			(layer "B.Fab")
		)
		(fp_line
			(start -0.120396 0.3048)
			(end -0.120396 0.2794)
			(stroke
				(width 0.1)
				(type default)
			)
			(layer "B.Fab")
		)
		(fp_line
			(start -0.67945 0.3048)
			(end -0.120396 0.3048)
			(stroke
				(width 0.1)
				(type default)
			)
			(layer "B.Fab")
		)
		(pad "1" smd circle
			(at 0.40005 0 270)
			(size 0 0)
			(layers "B.Cu" "B.Mask" "B.Paste")
			(net "GPU_3V3IO_RSVD1_FFU")
		)
		(pad "2" smd circle
			(at -0.40005 0 270)
			(size 0 0)
			(layers "B.Cu" "B.Mask" "B.Paste")
			(net "GND")
		)
	)
	(footprint ""
		(layer "B.Cu")
		(at 383.224278 -137.535158 90)
		(property "Reference" "PC12"
			(at 0 0 90)
			(layer "B.SilkS")
			(hide yes)
			(effects
				(font
					(size 1.27 1.27)
				)
				(justify mirror)
			)
		)
		(property "Value" ""
			(at 0 0 90)
			(layer "B.Fab")
			(effects
				(font
					(size 1.27 1.27)
				)
				(justify mirror)
			)
		)
		(duplicate_pad_numbers_are_jumpers no)
		(fp_line
			(start 0.7874 -0.4064)
			(end -0.7874 -0.4064)
			(stroke
				(width 0.1524)
				(type default)
			)
			(layer "B.SilkS")
		)
		(fp_line
			(start -0.7874 -0.4064)
			(end -0.7874 0.4064)
			(stroke
				(width 0.1524)
				(type default)
			)
			(layer "B.SilkS")
		)
		(fp_line
			(start 0.7874 0.4064)
			(end 0.7874 -0.4064)
			(stroke
				(width 0.1524)
				(type default)
			)
			(layer "B.SilkS")
		)
		(fp_line
			(start -0.7874 0.4064)
			(end 0.7874 0.4064)
			(stroke
				(width 0.1524)
				(type default)
			)
			(layer "B.SilkS")
		)
		(fp_line
			(start 0.67945 -0.305054)
			(end 0.12065 -0.305054)
			(stroke
				(width 0.1)
				(type default)
			)
			(layer "B.Fab")
		)
		(fp_line
			(start 0.12065 -0.305054)
			(end 0.12065 -0.2794)
			(stroke
				(width 0.1)
				(type default)
			)
			(layer "B.Fab")
		)
		(fp_line
			(start -0.12065 -0.3048)
			(end -0.67945 -0.3048)
			(stroke
				(width 0.1)
				(type default)
			)
			(layer "B.Fab")
		)
		(fp_line
			(start -0.67945 -0.3048)
			(end -0.67945 0.3048)
			(stroke
				(width 0.1)
				(type default)
			)
			(layer "B.Fab")
		)
		(fp_line
			(start 0.12065 -0.2794)
			(end -0.12065 -0.2794)
			(stroke
				(width 0.1)
				(type default)
			)
			(layer "B.Fab")
		)
		(fp_line
			(start -0.12065 -0.2794)
			(end -0.12065 -0.3048)
			(stroke
				(width 0.1)
				(type default)
			)
			(layer "B.Fab")
		)
		(fp_line
			(start 0.12065 0.2794)
			(end 0.12065 0.3048)
			(stroke
				(width 0.1)
				(type default)
			)
			(layer "B.Fab")
		)
		(fp_line
			(start -0.120396 0.2794)
			(end 0.12065 0.2794)
			(stroke
				(width 0.1)
				(type default)
			)
			(layer "B.Fab")
		)
		(fp_line
			(start 0.67945 0.3048)
			(end 0.67945 -0.305054)
			(stroke
				(width 0.1)
				(type default)
			)
			(layer "B.Fab")
		)
		(fp_line
			(start 0.12065 0.3048)
			(end 0.67945 0.3048)
			(stroke
				(width 0.1)
				(type default)
			)
			(layer "B.Fab")
		)
		(fp_line
			(start -0.120396 0.3048)
			(end -0.120396 0.2794)
			(stroke
				(width 0.1)
				(type default)
			)
			(layer "B.Fab")
		)
		(fp_line
			(start -0.67945 0.3048)
			(end -0.120396 0.3048)
			(stroke
				(width 0.1)
				(type default)
			)
			(layer "B.Fab")
		)
		(pad "1" smd circle
			(at 0.40005 0 270)
			(size 0 0)
			(layers "B.Cu" "B.Mask" "B.Paste")
			(net "PVDDCR_CPU0_P0_VCC")
		)
		(pad "2" smd circle
			(at -0.40005 0 270)
			(size 0 0)
			(layers "B.Cu" "B.Mask" "B.Paste")
			(net "GND")
		)
	)
	(footprint ""
		(layer "B.Cu")
		(at 171.196 -116.296948)
		(property "Reference" "R889"
			(at 0 0 0)
			(layer "B.SilkS")
			(hide yes)
			(effects
				(font
					(size 1.27 1.27)
				)
				(justify mirror)
			)
		)
		(property "Value" ""
			(at 0 0 0)
			(layer "B.Fab")
			(effects
				(font
					(size 1.27 1.27)
				)
				(justify mirror)
			)
		)
		(duplicate_pad_numbers_are_jumpers no)
		(fp_line
			(start -0.7874 -0.4064)
			(end -0.7874 0.4064)
			(stroke
				(width 0.1524)
				(type default)
			)
			(layer "B.SilkS")
		)
		(fp_line
			(start -0.7874 0.4064)
			(end 0.7874 0.4064)
			(stroke
				(width 0.1524)
				(type default)
			)
			(layer "B.SilkS")
		)
		(fp_line
			(start 0.7874 -0.4064)
			(end -0.7874 -0.4064)
			(stroke
				(width 0.1524)
				(type default)
			)
			(layer "B.SilkS")
		)
		(fp_line
			(start 0.7874 0.4064)
			(end 0.7874 -0.4064)
			(stroke
				(width 0.1524)
				(type default)
			)
			(layer "B.SilkS")
		)
		(fp_line
			(start -0.67945 -0.3048)
			(end -0.67945 0.3048)
			(stroke
				(width 0.1)
				(type default)
			)
			(layer "B.Fab")
		)
		(fp_line
			(start -0.67945 0.3048)
			(end -0.120396 0.3048)
			(stroke
				(width 0.1)
				(type default)
			)
			(layer "B.Fab")
		)
		(fp_line
			(start -0.12065 -0.3048)
			(end -0.67945 -0.3048)
			(stroke
				(width 0.1)
				(type default)
			)
			(layer "B.Fab")
		)
		(fp_line
			(start -0.12065 -0.2794)
			(end -0.12065 -0.3048)
			(stroke
				(width 0.1)
				(type default)
			)
			(layer "B.Fab")
		)
		(fp_line
			(start -0.120396 0.2794)
			(end 0.12065 0.2794)
			(stroke
				(width 0.1)
				(type default)
			)
			(layer "B.Fab")
		)
		(fp_line
			(start -0.120396 0.3048)
			(end -0.120396 0.2794)
			(stroke
				(width 0.1)
				(type default)
			)
			(layer "B.Fab")
		)
		(fp_line
			(start 0.12065 -0.305054)
			(end 0.12065 -0.2794)
			(stroke
				(width 0.1)
				(type default)
			)
			(layer "B.Fab")
		)
		(fp_line
			(start 0.12065 -0.2794)
			(end -0.12065 -0.2794)
			(stroke
				(width 0.1)
				(type default)
			)
			(layer "B.Fab")
		)
		(fp_line
			(start 0.12065 0.2794)
			(end 0.12065 0.3048)
			(stroke
				(width 0.1)
				(type default)
			)
			(layer "B.Fab")
		)
		(fp_line
			(start 0.12065 0.3048)
			(end 0.67945 0.3048)
			(stroke
				(width 0.1)
				(type default)
			)
			(layer "B.Fab")
		)
		(fp_line
			(start 0.67945 -0.305054)
			(end 0.12065 -0.305054)
			(stroke
				(width 0.1)
				(type default)
			)
			(layer "B.Fab")
		)
		(fp_line
			(start 0.67945 0.3048)
			(end 0.67945 -0.305054)
			(stroke
				(width 0.1)
				(type default)
			)
			(layer "B.Fab")
		)
		(pad "1" smd circle
			(at 0.40005 0 180)
			(size 0 0)
			(layers "B.Cu" "B.Mask" "B.Paste")
			(net "SCM_SPARE_0")
		)
		(pad "2" smd circle
			(at -0.40005 0 180)
			(size 0 0)
			(layers "B.Cu" "B.Mask" "B.Paste")
			(net "GND")
		)
	)
	(footprint ""
		(layer "B.Cu")
		(at 360.579924 -395.127988 -90)
		(property "Reference" "C591"
			(at 0 0 90)
			(layer "B.SilkS")
			(hide yes)
			(effects
				(font
					(size 1.27 1.27)
				)
				(justify mirror)
			)
		)
		(property "Value" ""
			(at 0 0 90)
			(layer "B.Fab")
			(effects
				(font
					(size 1.27 1.27)
				)
				(justify mirror)
			)
		)
		(duplicate_pad_numbers_are_jumpers no)
		(fp_line
			(start -0.7874 0.4064)
			(end 0.7874 0.4064)
			(stroke
				(width 0.1524)
				(type default)
			)
			(layer "B.SilkS")
		)
		(fp_line
			(start 0.7874 0.4064)
			(end 0.7874 -0.4064)
			(stroke
				(width 0.1524)
				(type default)
			)
			(layer "B.SilkS")
		)
		(fp_line
			(start -0.7874 -0.4064)
			(end -0.7874 0.4064)
			(stroke
				(width 0.1524)
				(type default)
			)
			(layer "B.SilkS")
		)
		(fp_line
			(start 0.7874 -0.4064)
			(end -0.7874 -0.4064)
			(stroke
				(width 0.1524)
				(type default)
			)
			(layer "B.SilkS")
		)
		(fp_line
			(start -0.67945 0.3048)
			(end -0.120396 0.3048)
			(stroke
				(width 0.1)
				(type default)
			)
			(layer "B.Fab")
		)
		(fp_line
			(start -0.120396 0.3048)
			(end -0.120396 0.2794)
			(stroke
				(width 0.1)
				(type default)
			)
			(layer "B.Fab")
		)
		(fp_line
			(start 0.12065 0.3048)
			(end 0.67945 0.3048)
			(stroke
				(width 0.1)
				(type default)
			)
			(layer "B.Fab")
		)
		(fp_line
			(start 0.67945 0.3048)
			(end 0.67945 -0.305054)
			(stroke
				(width 0.1)
				(type default)
			)
			(layer "B.Fab")
		)
		(fp_line
			(start -0.120396 0.2794)
			(end 0.12065 0.2794)
			(stroke
				(width 0.1)
				(type default)
			)
			(layer "B.Fab")
		)
		(fp_line
			(start 0.12065 0.2794)
			(end 0.12065 0.3048)
			(stroke
				(width 0.1)
				(type default)
			)
			(layer "B.Fab")
		)
		(fp_line
			(start -0.12065 -0.2794)
			(end -0.12065 -0.3048)
			(stroke
				(width 0.1)
				(type default)
			)
			(layer "B.Fab")
		)
		(fp_line
			(start 0.12065 -0.2794)
			(end -0.12065 -0.2794)
			(stroke
				(width 0.1)
				(type default)
			)
			(layer "B.Fab")
		)
		(fp_line
			(start -0.67945 -0.3048)
			(end -0.67945 0.3048)
			(stroke
				(width 0.1)
				(type default)
			)
			(layer "B.Fab")
		)
		(fp_line
			(start -0.12065 -0.3048)
			(end -0.67945 -0.3048)
			(stroke
				(width 0.1)
				(type default)
			)
			(layer "B.Fab")
		)
		(fp_line
			(start 0.12065 -0.305054)
			(end 0.12065 -0.2794)
			(stroke
				(width 0.1)
				(type default)
			)
			(layer "B.Fab")
		)
		(fp_line
			(start 0.67945 -0.305054)
			(end 0.12065 -0.305054)
			(stroke
				(width 0.1)
				(type default)
			)
			(layer "B.Fab")
		)
		(pad "1" smd circle
			(at 0.40005 0 90)
			(size 0 0)
			(layers "B.Cu" "B.Mask" "B.Paste")
			(net "P1V8_CPU0_RT_1D")
		)
		(pad "2" smd circle
			(at -0.40005 0 90)
			(size 0 0)
			(layers "B.Cu" "B.Mask" "B.Paste")
			(net "GND")
		)
	)
	(footprint ""
		(layer "B.Cu")
		(at 195.199 -137.632948 -90)
		(property "Reference" "R1616"
			(at 0 0 90)
			(layer "B.SilkS")
			(hide yes)
			(effects
				(font
					(size 1.27 1.27)
				)
				(justify mirror)
			)
		)
		(property "Value" ""
			(at 0 0 90)
			(layer "B.Fab")
			(effects
				(font
					(size 1.27 1.27)
				)
				(justify mirror)
			)
		)
		(duplicate_pad_numbers_are_jumpers no)
		(fp_line
			(start -0.7874 0.4064)
			(end 0.7874 0.4064)
			(stroke
				(width 0.1524)
				(type default)
			)
			(layer "B.SilkS")
		)
		(fp_line
			(start 0.7874 0.4064)
			(end 0.7874 -0.4064)
			(stroke
				(width 0.1524)
				(type default)
			)
			(layer "B.SilkS")
		)
		(fp_line
			(start -0.7874 -0.4064)
			(end -0.7874 0.4064)
			(stroke
				(width 0.1524)
				(type default)
			)
			(layer "B.SilkS")
		)
		(fp_line
			(start 0.7874 -0.4064)
			(end -0.7874 -0.4064)
			(stroke
				(width 0.1524)
				(type default)
			)
			(layer "B.SilkS")
		)
		(fp_line
			(start -0.67945 0.3048)
			(end -0.120396 0.3048)
			(stroke
				(width 0.1)
				(type default)
			)
			(layer "B.Fab")
		)
		(fp_line
			(start -0.120396 0.3048)
			(end -0.120396 0.2794)
			(stroke
				(width 0.1)
				(type default)
			)
			(layer "B.Fab")
		)
		(fp_line
			(start 0.12065 0.3048)
			(end 0.67945 0.3048)
			(stroke
				(width 0.1)
				(type default)
			)
			(layer "B.Fab")
		)
		(fp_line
			(start 0.67945 0.3048)
			(end 0.67945 -0.305054)
			(stroke
				(width 0.1)
				(type default)
			)
			(layer "B.Fab")
		)
		(fp_line
			(start -0.120396 0.2794)
			(end 0.12065 0.2794)
			(stroke
				(width 0.1)
				(type default)
			)
			(layer "B.Fab")
		)
		(fp_line
			(start 0.12065 0.2794)
			(end 0.12065 0.3048)
			(stroke
				(width 0.1)
				(type default)
			)
			(layer "B.Fab")
		)
		(fp_line
			(start -0.12065 -0.2794)
			(end -0.12065 -0.3048)
			(stroke
				(width 0.1)
				(type default)
			)
			(layer "B.Fab")
		)
		(fp_line
			(start 0.12065 -0.2794)
			(end -0.12065 -0.2794)
			(stroke
				(width 0.1)
				(type default)
			)
			(layer "B.Fab")
		)
		(fp_line
			(start -0.67945 -0.3048)
			(end -0.67945 0.3048)
			(stroke
				(width 0.1)
				(type default)
			)
			(layer "B.Fab")
		)
		(fp_line
			(start -0.12065 -0.3048)
			(end -0.67945 -0.3048)
			(stroke
				(width 0.1)
				(type default)
			)
			(layer "B.Fab")
		)
		(fp_line
			(start 0.12065 -0.305054)
			(end 0.12065 -0.2794)
			(stroke
				(width 0.1)
				(type default)
			)
			(layer "B.Fab")
		)
		(fp_line
			(start 0.67945 -0.305054)
			(end 0.12065 -0.305054)
			(stroke
				(width 0.1)
				(type default)
			)
			(layer "B.Fab")
		)
		(pad "1" smd circle
			(at 0.40005 0 90)
			(size 0 0)
			(layers "B.Cu" "B.Mask" "B.Paste")
			(net "FM_ROM_SD_LS_OE")
		)
		(pad "2" smd circle
			(at -0.40005 0 90)
			(size 0 0)
			(layers "B.Cu" "B.Mask" "B.Paste")
			(net "ROM_SD_LS_OE")
		)
	)
	(footprint ""
		(layer "B.Cu")
		(at 280.636218 -192.660016 180)
		(property "Reference" "C149"
			(at 0 0 0)
			(layer "B.SilkS")
			(hide yes)
			(effects
				(font
					(size 1.27 1.27)
				)
				(justify mirror)
			)
		)
		(property "Value" ""
			(at 0 0 0)
			(layer "B.Fab")
			(effects
				(font
					(size 1.27 1.27)
				)
				(justify mirror)
			)
		)
		(duplicate_pad_numbers_are_jumpers no)
		(fp_line
			(start 1.524 0.762)
			(end 1.524 -0.762)
			(stroke
				(width 0.1524)
				(type default)
			)
			(layer "B.SilkS")
		)
		(fp_line
			(start 1.524 -0.762)
			(end -1.524 -0.762)
			(stroke
				(width 0.1524)
				(type default)
			)
			(layer "B.SilkS")
		)
		(fp_line
			(start -1.524 0.762)
			(end 1.524 0.762)
			(stroke
				(width 0.1524)
				(type default)
			)
			(layer "B.SilkS")
		)
		(fp_line
			(start -1.524 -0.762)
			(end -1.524 0.762)
			(stroke
				(width 0.1524)
				(type default)
			)
			(layer "B.SilkS")
		)
		(fp_line
			(start 1.1049 0.724916)
			(end -1.1049 0.724916)
			(stroke
				(width 0.1)
				(type default)
			)
			(layer "B.Fab")
		)
		(fp_line
			(start 1.1049 -0.724916)
			(end 1.1049 0.724916)
			(stroke
				(width 0.1)
				(type default)
			)
			(layer "B.Fab")
		)
		(fp_line
			(start -1.1049 0.724916)
			(end -1.1049 -0.724916)
			(stroke
				(width 0.1)
				(type default)
			)
			(layer "B.Fab")
		)
		(fp_line
			(start -1.1049 -0.724916)
			(end 1.1049 -0.724916)
			(stroke
				(width 0.1)
				(type default)
			)
			(layer "B.Fab")
		)
		(pad "1" smd rect
			(at 0.889 0 180)
			(size 1.016 1.27)
			(layers "B.Cu" "B.Mask" "B.Paste")
			(net "P12V_MEM_CPU0")
		)
		(pad "2" smd rect
			(at -0.889 0 180)
			(size 1.016 1.27)
			(layers "B.Cu" "B.Mask" "B.Paste")
			(net "GND")
		)
	)
	(footprint ""
		(layer "B.Cu")
		(at 313.118246 -396.393162 -90)
		(property "Reference" "C519"
			(at 0 0 90)
			(layer "B.SilkS")
			(hide yes)
			(effects
				(font
					(size 1.27 1.27)
				)
				(justify mirror)
			)
		)
		(property "Value" ""
			(at 0 0 90)
			(layer "B.Fab")
			(effects
				(font
					(size 1.27 1.27)
				)
				(justify mirror)
			)
		)
		(duplicate_pad_numbers_are_jumpers no)
		(fp_line
			(start -0.299974 0.150114)
			(end 0.299974 0.150114)
			(stroke
				(width 0.1)
				(type default)
			)
			(layer "B.Fab")
		)
		(fp_line
			(start 0.299974 0.150114)
			(end 0.299974 -0.150114)
			(stroke
				(width 0.1)
				(type default)
			)
			(layer "B.Fab")
		)
		(fp_line
			(start -0.299974 -0.150114)
			(end -0.299974 0.150114)
			(stroke
				(width 0.1)
				(type default)
			)
			(layer "B.Fab")
		)
		(fp_line
			(start 0.299974 -0.150114)
			(end -0.299974 -0.150114)
			(stroke
				(width 0.1)
				(type default)
			)
			(layer "B.Fab")
		)
		(pad "1" smd rect
			(at 0.2667 0 90)
			(size 0.3048 0.381)
			(layers "B.Cu" "B.Mask" "B.Paste")
			(net "P1V8_CPU0_RT0_1A")
		)
		(pad "2" smd rect
			(at -0.2667 0 90)
			(size 0.3048 0.381)
			(layers "B.Cu" "B.Mask" "B.Paste")
			(net "GND")
		)
	)
)
